# S9S_MB_2U (Grand Teton) — schematic netlist excerpt (pin names and nets, part order shuffled) for the footprints in the layout excerpt that follows; sources: Cadence DE-HDL packaged netlist, KiCad conversion of 03242023_DA0F0TMBIJ0_F0T_Motherboard_J_brd_V01_OCP.brd

D71  Q_LED  IC  pkg SMLF  page 256 : A = LED_RST_PLD_CPU1_DRAM_EF_N ; C = LED_RST_PLD_CPU1_DRAM_EF_N_D
C2253  Q_CAP  0.1UF 25V 10% X7R  pkg 0402  page 225 : A = P0V62_CPU1_RST_DDR_VREF ; B = GND
C689  Q_CAP_DIFFBUS  DIFF BUS_0.22UF 6.3V 20% X6S  pkg C0201  page 177 : \1\ = P5E_CPU1_PE4_TX_C_DP<10> ; \2\ = P5E_CPU1_PE4_TX_DP<10>

(kicad_pcb
	(version 20260206)
	(generator "pcbnew")
	(generator_version "10.0")
	(general
		(thickness 1.6)
		(legacy_teardrops no)
	)
	(paper "A4")
	(title_block
		(title "03242023_DA0F0TMBIJ0_F0T_Motherboard_J_brd_V01_OCP.brd")
		(comment 1 "Grand Teton / footprints 3862-3864 of 6105")
	)
	(layers
		(0 "F.Cu" signal "TOP")
		(4 "In1.Cu" signal "GND")
		(6 "In2.Cu" signal "IN1")
		(8 "In3.Cu" signal "GND1")
		(10 "In4.Cu" signal "IN2")
		(12 "In5.Cu" signal "GND2")
		(14 "In6.Cu" signal "IN3")
		(16 "In7.Cu" signal "GND3")
		(18 "In8.Cu" signal "VCC")
		(20 "In9.Cu" signal "VCC1")
		(22 "In10.Cu" signal "GND4")
		(24 "In11.Cu" signal "IN4")
		(26 "In12.Cu" signal "GND5")
		(28 "In13.Cu" signal "IN5")
		(30 "In14.Cu" signal "GND6")
		(32 "In15.Cu" signal "IN6")
		(34 "In16.Cu" signal "GND7")
		(2 "B.Cu" signal "BOTTOM")
		(9 "F.Adhes" user "F.Adhesive")
		(11 "B.Adhes" user "B.Adhesive")
		(13 "F.Paste" user "Package Geometry/Pastemask Top")
		(15 "B.Paste" user "Package Geometry/Pastemask Bottom")
		(5 "F.SilkS" user "Ref Des/Silkscreen Top")
		(7 "B.SilkS" user "Ref Des/Silkscreen Bottom")
		(1 "F.Mask" user "Board Geometry/Soldermask Top")
		(3 "B.Mask" user "Board Geometry/Soldermask Bottom")
		(17 "Dwgs.User" user "User.Drawings")
		(19 "Cmts.User" user "User.Comments")
		(21 "Eco1.User" user "User.Eco1")
		(23 "Eco2.User" user "User.Eco2")
		(25 "Edge.Cuts" user "Board Geometry/Outline")
		(27 "Margin" user)
		(31 "F.CrtYd" user "Package Geometry/Place Bound Top")
		(29 "B.CrtYd" user "Package Geometry/Place Bound Bottom")
		(35 "F.Fab" user "Ref Des/Assembly Top")
		(33 "B.Fab" user "Ref Des/Assembly Bottom")
	)
	(footprint ""
		(layer "F.Cu")
		(at 61.778896 -70.78599)
		(property "Reference" "D71"
			(at -33.207706 50.178462 90)
			(unlocked yes)
			(layer "F.SilkS")
			(effects
				(font
					(size 0.635 0.4064)
					(thickness 0.1524)
				)
				(justify left)
			)
		)
		(property "Value" ""
			(at 0 0 0)
			(layer "F.Fab")
			(effects
				(font
					(size 1.27 1.27)
				)
			)
		)
		(duplicate_pad_numbers_are_jumpers no)
		(fp_line
			(start -0.90678 0.4826)
			(end -0.90678 -0.4699)
			(stroke
				(width 0.1524)
				(type default)
			)
			(layer "F.SilkS")
		)
		(fp_line
			(start -0.89408 -0.4826)
			(end 0.90678 -0.4826)
			(stroke
				(width 0.1524)
				(type default)
			)
			(layer "F.SilkS")
		)
		(fp_line
			(start -0.79248 -0.4826)
			(end 1.03378 -0.4826)
			(stroke
				(width 0.1524)
				(type default)
			)
			(layer "F.SilkS")
		)
		(fp_line
			(start -0.64008 -0.4826)
			(end 1.16078 -0.4826)
			(stroke
				(width 0.1524)
				(type default)
			)
			(layer "F.SilkS")
		)
		(fp_line
			(start 0.90678 -0.4826)
			(end 0.90678 0.4826)
			(stroke
				(width 0.1524)
				(type default)
			)
			(layer "F.SilkS")
		)
		(fp_line
			(start 0.90678 0.4826)
			(end -0.90678 0.4826)
			(stroke
				(width 0.1524)
				(type default)
			)
			(layer "F.SilkS")
		)
		(fp_line
			(start 1.03378 -0.4826)
			(end 1.03378 0.4826)
			(stroke
				(width 0.1524)
				(type default)
			)
			(layer "F.SilkS")
		)
		(fp_line
			(start 1.03378 0.4826)
			(end -0.79248 0.4826)
			(stroke
				(width 0.1524)
				(type default)
			)
			(layer "F.SilkS")
		)
		(fp_line
			(start 1.16078 -0.4826)
			(end 1.16078 0.4826)
			(stroke
				(width 0.1524)
				(type default)
			)
			(layer "F.SilkS")
		)
		(fp_line
			(start 1.16078 0.4826)
			(end -0.64008 0.4826)
			(stroke
				(width 0.1524)
				(type default)
			)
			(layer "F.SilkS")
		)
		(fp_line
			(start -0.499872 -0.249936)
			(end 0.499872 -0.249936)
			(stroke
				(width 0.1)
				(type default)
			)
			(layer "F.Fab")
		)
		(fp_line
			(start -0.499872 0.249936)
			(end -0.499872 -0.249936)
			(stroke
				(width 0.1)
				(type default)
			)
			(layer "F.Fab")
		)
		(fp_line
			(start 0.499872 -0.249936)
			(end 0.499872 0.249936)
			(stroke
				(width 0.1)
				(type default)
			)
			(layer "F.Fab")
		)
		(fp_line
			(start 0.499872 0.249936)
			(end -0.499872 0.249936)
			(stroke
				(width 0.1)
				(type default)
			)
			(layer "F.Fab")
		)
		(pad "A" smd rect
			(at -0.47498 0)
			(size 0.6096 0.7112)
			(layers "F.Cu" "F.Mask" "F.Paste")
			(net "LED_RST_PLD_CPU1_DRAM_EF_N")
		)
		(pad "C" smd rect
			(at 0.47498 0)
			(size 0.6096 0.7112)
			(layers "F.Cu" "F.Mask" "F.Paste")
			(net "LED_RST_PLD_CPU1_DRAM_EF_N_D")
		)
	)
	(footprint ""
		(layer "F.Cu")
		(at 80.847438 -408.517344 -90)
		(property "Reference" "C689"
			(at 0 0 270)
			(layer "F.SilkS")
			(hide yes)
			(effects
				(font
					(size 1.27 1.27)
				)
			)
		)
		(property "Value" ""
			(at 0 0 270)
			(layer "F.Fab")
			(effects
				(font
					(size 1.27 1.27)
				)
			)
		)
		(duplicate_pad_numbers_are_jumpers no)
		(fp_line
			(start -0.299974 0.150114)
			(end -0.299974 -0.150114)
			(stroke
				(width 0.1)
				(type default)
			)
			(layer "F.Fab")
		)
		(fp_line
			(start 0.299974 0.150114)
			(end -0.299974 0.150114)
			(stroke
				(width 0.1)
				(type default)
			)
			(layer "F.Fab")
		)
		(fp_line
			(start -0.299974 -0.150114)
			(end 0.299974 -0.150114)
			(stroke
				(width 0.1)
				(type default)
			)
			(layer "F.Fab")
		)
		(fp_line
			(start 0.299974 -0.150114)
			(end 0.299974 0.150114)
			(stroke
				(width 0.1)
				(type default)
			)
			(layer "F.Fab")
		)
		(pad "1" smd rect
			(at -0.2667 0 270)
			(size 0.3048 0.381)
			(layers "F.Cu" "F.Mask" "F.Paste")
			(net "P5E_CPU1_PE4_TX_C_DP<10>")
		)
		(pad "2" smd rect
			(at 0.2667 0 270)
			(size 0.3048 0.381)
			(layers "F.Cu" "F.Mask" "F.Paste")
			(net "P5E_CPU1_PE4_TX_DP<10>")
		)
	)
	(footprint ""
		(layer "F.Cu")
		(at 123.994926 -122.096784 90)
		(property "Reference" "C2253"
			(at 0 0 90)
			(layer "F.SilkS")
			(hide yes)
			(effects
				(font
					(size 1.27 1.27)
				)
			)
		)
		(property "Value" ""
			(at 0 0 90)
			(layer "F.Fab")
			(effects
				(font
					(size 1.27 1.27)
				)
			)
		)
		(duplicate_pad_numbers_are_jumpers no)
		(fp_line
			(start 0.7874 -0.4064)
			(end 0.7874 0.4064)
			(stroke
				(width 0.1524)
				(type default)
			)
			(layer "F.SilkS")
		)
		(fp_line
			(start -0.7874 -0.4064)
			(end 0.7874 -0.4064)
			(stroke
				(width 0.1524)
				(type default)
			)
			(layer "F.SilkS")
		)
		(fp_line
			(start 0.7874 0.4064)
			(end -0.7874 0.4064)
			(stroke
				(width 0.1524)
				(type default)
			)
			(layer "F.SilkS")
		)
		(fp_line
			(start -0.7874 0.4064)
			(end -0.7874 -0.4064)
			(stroke
				(width 0.1524)
				(type default)
			)
			(layer "F.SilkS")
		)
		(fp_line
			(start -0.12065 -0.305054)
			(end -0.12065 -0.2794)
			(stroke
				(width 0.1)
				(type default)
			)
			(layer "F.Fab")
		)
		(fp_line
			(start -0.67945 -0.305054)
			(end -0.12065 -0.305054)
			(stroke
				(width 0.1)
				(type default)
			)
			(layer "F.Fab")
		)
		(fp_line
			(start 0.67945 -0.3048)
			(end 0.67945 0.3048)
			(stroke
				(width 0.1)
				(type default)
			)
			(layer "F.Fab")
		)
		(fp_line
			(start 0.12065 -0.3048)
			(end 0.67945 -0.3048)
			(stroke
				(width 0.1)
				(type default)
			)
			(layer "F.Fab")
		)
		(fp_line
			(start 0.12065 -0.2794)
			(end 0.12065 -0.3048)
			(stroke
				(width 0.1)
				(type default)
			)
			(layer "F.Fab")
		)
		(fp_line
			(start -0.12065 -0.2794)
			(end 0.12065 -0.2794)
			(stroke
				(width 0.1)
				(type default)
			)
			(layer "F.Fab")
		)
		(fp_line
			(start 0.120396 0.2794)
			(end -0.12065 0.2794)
			(stroke
				(width 0.1)
				(type default)
			)
			(layer "F.Fab")
		)
		(fp_line
			(start -0.12065 0.2794)
			(end -0.12065 0.3048)
			(stroke
				(width 0.1)
				(type default)
			)
			(layer "F.Fab")
		)
		(fp_line
			(start 0.67945 0.3048)
			(end 0.120396 0.3048)
			(stroke
				(width 0.1)
				(type default)
			)
			(layer "F.Fab")
		)
		(fp_line
			(start 0.120396 0.3048)
			(end 0.120396 0.2794)
			(stroke
				(width 0.1)
				(type default)
			)
			(layer "F.Fab")
		)
		(fp_line
			(start -0.12065 0.3048)
			(end -0.67945 0.3048)
			(stroke
				(width 0.1)
				(type default)
			)
			(layer "F.Fab")
		)
		(fp_line
			(start -0.67945 0.3048)
			(end -0.67945 -0.305054)
			(stroke
				(width 0.1)
				(type default)
			)
			(layer "F.Fab")
		)
		(pad "1" smd circle
			(at -0.40005 0 90)
			(size 0 0)
			(layers "F.Cu" "F.Mask" "F.Paste")
			(net "P0V62_CPU1_RST_DDR_VREF")
		)
		(pad "2" smd circle
			(at 0.40005 0 90)
			(size 0 0)
			(layers "F.Cu" "F.Mask" "F.Paste")
			(net "GND")
		)
	)
)
